(kicad_pcb
	(version 20260206)
	(generator "pcbnew")
	(generator_version "10.0")
	(general
		(thickness 1.6)
		(legacy_teardrops no)
	)
	(paper "A4")
	(title_block
		(title "Bryce Canyon_F.DPB_16315-1-OCP.brd")
		(comment 1 "Bryce Canyon / footprints 408-415 of 2223")
	)
	(layers
		(0 "F.Cu" signal "TOP")
		(4 "In1.Cu" signal "L2GND")
		(6 "In2.Cu" signal "L3")
		(8 "In3.Cu" signal "L4GND")
		(10 "In4.Cu" signal "L5")
		(12 "In5.Cu" signal "L6VCC")
		(14 "In6.Cu" signal "L7VCC")
		(16 "In7.Cu" signal "L8")
		(18 "In8.Cu" signal "L9GND")
		(20 "In9.Cu" signal "L10")
		(22 "In10.Cu" signal "L11GND")
		(2 "B.Cu" signal "BOTTOM")
		(9 "F.Adhes" user "F.Adhesive")
		(11 "B.Adhes" user "B.Adhesive")
		(13 "F.Paste" user "Package Geometry/Pastemask Top")
		(15 "B.Paste" user "Package Geometry/Pastemask Bottom")
		(5 "F.SilkS" user "Ref Des/Silkscreen Top")
		(7 "B.SilkS" user "Ref Des/Silkscreen Bottom")
		(1 "F.Mask" user "Board Geometry/Soldermask Top")
		(3 "B.Mask" user "Board Geometry/Soldermask Bottom")
		(17 "Dwgs.User" user "User.Drawings")
		(19 "Cmts.User" user "User.Comments")
		(21 "Eco1.User" user "User.Eco1")
		(23 "Eco2.User" user "User.Eco2")
		(25 "Edge.Cuts" user "Board Geometry/Outline")
		(27 "Margin" user)
		(31 "F.CrtYd" user "Package Geometry/Place Bound Top")
		(29 "B.CrtYd" user "Package Geometry/Place Bound Bottom")
		(35 "F.Fab" user "Ref Des/Assembly Top")
		(33 "B.Fab" user "Ref Des/Assembly Bottom")
	)
	(footprint ""
		(layer "F.Cu")
		(at 468.354918 -164.701474)
		(property "Reference" "R674"
			(at 0 0 0)
			(layer "F.SilkS")
			(hide yes)
			(effects
				(font
					(size 1.27 1.27)
				)
			)
		)
		(property "Value" "4K7R2J-2-GP"
			(at 0.064008 -3.993896 0)
			(unlocked yes)
			(layer "F.Fab")
			(hide yes)
			(effects
				(font
					(size 1.016 1.016)
					(thickness 0.1524)
				)
			)
		)
		(property "Device Type" "R402H16"
			(at 0.064008 -5.517896 0)
			(unlocked yes)
			(layer "F.Fab")
			(hide yes)
			(effects
				(font
					(size 1.016 1.016)
					(thickness 0.1524)
				)
			)
		)
		(duplicate_pad_numbers_are_jumpers no)
		(fp_line
			(start -0.508 -0.9398)
			(end -0.508 0.9398)
			(stroke
				(width 0.1524)
				(type default)
			)
			(layer "F.SilkS")
		)
		(fp_line
			(start 0.508 -0.9398)
			(end -0.508 -0.9398)
			(stroke
				(width 0.1524)
				(type default)
			)
			(layer "F.SilkS")
		)
		(fp_rect
			(start -0.508 0.9398)
			(end 0.508 -0.9398)
			(stroke
				(width 0)
				(type default)
			)
			(fill no)
			(layer "F.CrtYd")
		)
		(fp_rect
			(start -0.508 0.9398)
			(end 0.508 -0.9398)
			(stroke
				(width 0)
				(type default)
			)
			(fill no)
			(layer "F.Fab")
		)
		(pad "1" smd custom
			(at 0 -0.4445)
			(size 0.1397 0.1397)
			(layers "F.Cu" "F.Mask" "F.Paste")
			(net "P12V_A")
			(options
				(clearance outline)
				(anchor circle)
			)
			(primitives
				(gr_poly
					(pts
						(arc
							(start -0.1778 -0.2794)
							(mid -0.249642 -0.249642)
							(end -0.2794 -0.1778)
						)
						(arc
							(start -0.2794 0.1778)
							(mid -0.249642 0.249642)
							(end -0.1778 0.2794)
						)
						(arc
							(start 0.1778 0.2794)
							(mid 0.249642 0.249642)
							(end 0.2794 0.1778)
						)
						(arc
							(start 0.2794 -0.1778)
							(mid 0.249642 -0.249642)
							(end 0.1778 -0.2794)
						)
					)
					(width 0)
					(fill yes)
				)
			)
		)
		(pad "2" smd custom
			(at 0 0.4445)
			(size 0.1397 0.1397)
			(layers "F.Cu" "F.Mask" "F.Paste")
			(net "SW_HDD_R23")
			(options
				(clearance outline)
				(anchor circle)
			)
			(primitives
				(gr_poly
					(pts
						(arc
							(start -0.1778 -0.2794)
							(mid -0.249642 -0.249642)
							(end -0.2794 -0.1778)
						)
						(arc
							(start -0.2794 0.1778)
							(mid -0.249642 0.249642)
							(end -0.1778 0.2794)
						)
						(arc
							(start 0.1778 0.2794)
							(mid 0.249642 0.249642)
							(end 0.2794 0.1778)
						)
						(arc
							(start 0.2794 -0.1778)
							(mid 0.249642 -0.249642)
							(end 0.1778 -0.2794)
						)
					)
					(width 0)
					(fill yes)
				)
			)
		)
	)
	(footprint ""
		(layer "F.Cu")
		(at 266.201398 -109.157262 -90)
		(property "Reference" "R361"
			(at 0 0 270)
			(layer "F.SilkS")
			(hide yes)
			(effects
				(font
					(size 1.27 1.27)
				)
			)
		)
		(property "Value" "0R2J-2-GP"
			(at 0.064008 -3.993896 270)
			(unlocked yes)
			(layer "F.Fab")
			(hide yes)
			(effects
				(font
					(size 1.016 1.016)
					(thickness 0.1524)
				)
			)
		)
		(property "Device Type" "R402H16"
			(at 0.064008 -5.517896 270)
			(unlocked yes)
			(layer "F.Fab")
			(hide yes)
			(effects
				(font
					(size 1.016 1.016)
					(thickness 0.1524)
				)
			)
		)
		(duplicate_pad_numbers_are_jumpers no)
		(fp_line
			(start -0.508 -0.9398)
			(end -0.508 0.9398)
			(stroke
				(width 0.1524)
				(type default)
			)
			(layer "F.SilkS")
		)
		(fp_line
			(start 0.508 -0.9398)
			(end -0.508 -0.9398)
			(stroke
				(width 0.1524)
				(type default)
			)
			(layer "F.SilkS")
		)
		(fp_rect
			(start -0.508 0.9398)
			(end 0.508 -0.9398)
			(stroke
				(width 0)
				(type default)
			)
			(fill no)
			(layer "F.CrtYd")
		)
		(fp_rect
			(start -0.508 0.9398)
			(end 0.508 -0.9398)
			(stroke
				(width 0)
				(type default)
			)
			(fill no)
			(layer "F.Fab")
		)
		(pad "1" smd custom
			(at 0 -0.4445 270)
			(size 0.1397 0.1397)
			(layers "F.Cu" "F.Mask" "F.Paste")
			(net "SLOT1_SVR_ID0_GPIO2")
			(options
				(clearance outline)
				(anchor circle)
			)
			(primitives
				(gr_poly
					(pts
						(arc
							(start -0.1778 -0.2794)
							(mid -0.249642 -0.249642)
							(end -0.2794 -0.1778)
						)
						(arc
							(start -0.2794 0.1778)
							(mid -0.249642 0.249642)
							(end -0.1778 0.2794)
						)
						(arc
							(start 0.1778 0.2794)
							(mid 0.249642 0.249642)
							(end 0.2794 0.1778)
						)
						(arc
							(start 0.2794 -0.1778)
							(mid 0.249642 -0.249642)
							(end 0.1778 -0.2794)
						)
					)
					(width 0)
					(fill yes)
				)
			)
		)
		(pad "2" smd custom
			(at 0 0.4445 270)
			(size 0.1397 0.1397)
			(layers "F.Cu" "F.Mask" "F.Paste")
			(net "COMP_B_EXP_B_SPARE_0")
			(options
				(clearance outline)
				(anchor circle)
			)
			(primitives
				(gr_poly
					(pts
						(arc
							(start -0.1778 -0.2794)
							(mid -0.249642 -0.249642)
							(end -0.2794 -0.1778)
						)
						(arc
							(start -0.2794 0.1778)
							(mid -0.249642 0.249642)
							(end -0.1778 0.2794)
						)
						(arc
							(start 0.1778 0.2794)
							(mid 0.249642 0.249642)
							(end 0.2794 0.1778)
						)
						(arc
							(start 0.2794 -0.1778)
							(mid 0.249642 -0.249642)
							(end 0.1778 -0.2794)
						)
					)
					(width 0)
					(fill yes)
				)
			)
		)
	)
	(footprint ""
		(layer "F.Cu")
		(at 461.9371 -160.735518 180)
		(property "Reference" "R653"
			(at 0 0 180)
			(layer "F.SilkS")
			(hide yes)
			(effects
				(font
					(size 1.27 1.27)
				)
			)
		)
		(property "Value" "0R2J-2-GP"
			(at 0.064008 -3.993896 180)
			(unlocked yes)
			(layer "F.Fab")
			(hide yes)
			(effects
				(font
					(size 1.016 1.016)
					(thickness 0.1524)
				)
			)
		)
		(property "Device Type" "R402H16"
			(at 0.064008 -5.517896 180)
			(unlocked yes)
			(layer "F.Fab")
			(hide yes)
			(effects
				(font
					(size 1.016 1.016)
					(thickness 0.1524)
				)
			)
		)
		(duplicate_pad_numbers_are_jumpers no)
		(fp_line
			(start 0.508 -0.9398)
			(end -0.508 -0.9398)
			(stroke
				(width 0.1524)
				(type default)
			)
			(layer "F.SilkS")
		)
		(fp_line
			(start -0.508 -0.9398)
			(end -0.508 0.9398)
			(stroke
				(width 0.1524)
				(type default)
			)
			(layer "F.SilkS")
		)
		(fp_rect
			(start -0.508 0.9398)
			(end 0.508 -0.9398)
			(stroke
				(width 0)
				(type default)
			)
			(fill no)
			(layer "F.CrtYd")
		)
		(fp_rect
			(start -0.508 0.9398)
			(end 0.508 -0.9398)
			(stroke
				(width 0)
				(type default)
			)
			(fill no)
			(layer "F.Fab")
		)
		(pad "1" smd custom
			(at 0 -0.4445 180)
			(size 0.1397 0.1397)
			(layers "F.Cu" "F.Mask" "F.Paste")
			(net "SW_HDD_G22")
			(options
				(clearance outline)
				(anchor circle)
			)
			(primitives
				(gr_poly
					(pts
						(arc
							(start -0.1778 -0.2794)
							(mid -0.249642 -0.249642)
							(end -0.2794 -0.1778)
						)
						(arc
							(start -0.2794 0.1778)
							(mid -0.249642 0.249642)
							(end -0.1778 0.2794)
						)
						(arc
							(start 0.1778 0.2794)
							(mid 0.249642 0.249642)
							(end 0.2794 0.1778)
						)
						(arc
							(start 0.2794 -0.1778)
							(mid 0.249642 -0.249642)
							(end 0.1778 -0.2794)
						)
					)
					(width 0)
					(fill yes)
				)
			)
		)
		(pad "2" smd custom
			(at 0 0.4445 180)
			(size 0.1397 0.1397)
			(layers "F.Cu" "F.Mask" "F.Paste")
			(net "SW_HDD_R22")
			(options
				(clearance outline)
				(anchor circle)
			)
			(primitives
				(gr_poly
					(pts
						(arc
							(start -0.1778 -0.2794)
							(mid -0.249642 -0.249642)
							(end -0.2794 -0.1778)
						)
						(arc
							(start -0.2794 0.1778)
							(mid -0.249642 0.249642)
							(end -0.1778 0.2794)
						)
						(arc
							(start 0.1778 0.2794)
							(mid 0.249642 0.249642)
							(end 0.2794 0.1778)
						)
						(arc
							(start 0.2794 -0.1778)
							(mid 0.249642 -0.249642)
							(end 0.1778 -0.2794)
						)
					)
					(width 0)
					(fill yes)
				)
			)
		)
	)
	(footprint ""
		(layer "F.Cu")
		(at 321.634612 -274.219416 -90)
		(property "Reference" "C116"
			(at 0 0 270)
			(layer "F.SilkS")
			(hide yes)
			(effects
				(font
					(size 1.27 1.27)
				)
			)
		)
		(property "Value" "SCD01U16V1KX-GP"
			(at -2.8321 -1.7399 270)
			(unlocked yes)
			(layer "F.Fab")
			(hide yes)
			(effects
				(font
					(size 1.016 1.016)
					(thickness 0.1524)
				)
			)
		)
		(property "Device Type" "C0201H13"
			(at -2.8321 -3.2639 270)
			(unlocked yes)
			(layer "F.Fab")
			(hide yes)
			(effects
				(font
					(size 1.016 1.016)
					(thickness 0.1524)
				)
			)
		)
		(duplicate_pad_numbers_are_jumpers no)
		(fp_rect
			(start -0.2794 0.6477)
			(end 0.2794 -0.6477)
			(stroke
				(width 0)
				(type default)
			)
			(fill no)
			(layer "F.CrtYd")
		)
		(fp_rect
			(start -0.2794 0.6477)
			(end 0.2794 -0.6477)
			(stroke
				(width 0)
				(type default)
			)
			(fill no)
			(layer "F.Fab")
		)
		(pad "1" smd custom
			(at 0 -0.2794 270)
			(size 0.0762 0.0762)
			(layers "F.Cu" "F.Mask" "F.Paste")
			(net "SAS_HDD_RX_N6")
			(options
				(clearance outline)
				(anchor circle)
			)
			(primitives
				(gr_poly
					(pts
						(arc
							(start 0.1524 -0.127)
							(mid 0.137521 -0.162921)
							(end 0.1016 -0.1778)
						)
						(arc
							(start -0.1016 -0.1778)
							(mid -0.137521 -0.162921)
							(end -0.1524 -0.127)
						)
						(arc
							(start -0.1524 0.127)
							(mid -0.137521 0.162921)
							(end -0.1016 0.1778)
						)
						(arc
							(start 0.1016 0.1778)
							(mid 0.137521 0.162921)
							(end 0.1524 0.127)
						)
					)
					(width 0)
					(fill yes)
				)
			)
		)
		(pad "2" smd custom
			(at 0 0.2794 270)
			(size 0.0762 0.0762)
			(layers "F.Cu" "F.Mask" "F.Paste")
			(net "PHY_SCC_A_TO_DRV_A_6_DN")
			(options
				(clearance outline)
				(anchor circle)
			)
			(primitives
				(gr_poly
					(pts
						(arc
							(start 0.1524 -0.127)
							(mid 0.137521 -0.162921)
							(end 0.1016 -0.1778)
						)
						(arc
							(start -0.1016 -0.1778)
							(mid -0.137521 -0.162921)
							(end -0.1524 -0.127)
						)
						(arc
							(start -0.1524 0.127)
							(mid -0.137521 0.162921)
							(end -0.1016 0.1778)
						)
						(arc
							(start 0.1016 0.1778)
							(mid 0.137521 0.162921)
							(end 0.1524 0.127)
						)
					)
					(width 0)
					(fill yes)
				)
			)
		)
	)
	(footprint ""
		(layer "F.Cu")
		(at 256.413 -301.244 180)
		(property "Reference" "R4"
			(at 0 0 180)
			(layer "F.SilkS")
			(hide yes)
			(effects
				(font
					(size 1.27 1.27)
				)
			)
		)
		(property "Value" "0R2J-2-GP"
			(at 0.064008 -3.993896 180)
			(unlocked yes)
			(layer "F.Fab")
			(hide yes)
			(effects
				(font
					(size 1.016 1.016)
					(thickness 0.1524)
				)
			)
		)
		(property "Device Type" "R402H16"
			(at 0.064008 -5.517896 180)
			(unlocked yes)
			(layer "F.Fab")
			(hide yes)
			(effects
				(font
					(size 1.016 1.016)
					(thickness 0.1524)
				)
			)
		)
		(duplicate_pad_numbers_are_jumpers no)
		(fp_line
			(start 0.508 -0.9398)
			(end -0.508 -0.9398)
			(stroke
				(width 0.1524)
				(type default)
			)
			(layer "F.SilkS")
		)
		(fp_line
			(start -0.508 -0.9398)
			(end -0.508 0.9398)
			(stroke
				(width 0.1524)
				(type default)
			)
			(layer "F.SilkS")
		)
		(fp_rect
			(start -0.508 0.9398)
			(end 0.508 -0.9398)
			(stroke
				(width 0)
				(type default)
			)
			(fill no)
			(layer "F.CrtYd")
		)
		(fp_rect
			(start -0.508 0.9398)
			(end 0.508 -0.9398)
			(stroke
				(width 0)
				(type default)
			)
			(fill no)
			(layer "F.Fab")
		)
		(pad "1" smd custom
			(at 0 -0.4445 180)
			(size 0.1397 0.1397)
			(layers "F.Cu" "F.Mask" "F.Paste")
			(net "EEPROM_SCL")
			(options
				(clearance outline)
				(anchor circle)
			)
			(primitives
				(gr_poly
					(pts
						(arc
							(start -0.1778 -0.2794)
							(mid -0.249642 -0.249642)
							(end -0.2794 -0.1778)
						)
						(arc
							(start -0.2794 0.1778)
							(mid -0.249642 0.249642)
							(end -0.1778 0.2794)
						)
						(arc
							(start 0.1778 0.2794)
							(mid 0.249642 0.249642)
							(end 0.2794 0.1778)
						)
						(arc
							(start 0.2794 -0.1778)
							(mid 0.249642 -0.249642)
							(end 0.1778 -0.2794)
						)
					)
					(width 0)
					(fill yes)
				)
			)
		)
		(pad "2" smd custom
			(at 0 0.4445 180)
			(size 0.1397 0.1397)
			(layers "F.Cu" "F.Mask" "F.Paste")
			(net "I2C_DPB_A_SCL_BUF")
			(options
				(clearance outline)
				(anchor circle)
			)
			(primitives
				(gr_poly
					(pts
						(arc
							(start -0.1778 -0.2794)
							(mid -0.249642 -0.249642)
							(end -0.2794 -0.1778)
						)
						(arc
							(start -0.2794 0.1778)
							(mid -0.249642 0.249642)
							(end -0.1778 0.2794)
						)
						(arc
							(start 0.1778 0.2794)
							(mid 0.249642 0.249642)
							(end 0.2794 0.1778)
						)
						(arc
							(start 0.2794 -0.1778)
							(mid 0.249642 -0.249642)
							(end 0.1778 -0.2794)
						)
					)
					(width 0)
					(fill yes)
				)
			)
		)
	)
	(footprint ""
		(layer "F.Cu")
		(at 396.672054 -69.419978 -90)
		(property "Reference" "R867"
			(at 0 0 270)
			(layer "F.SilkS")
			(hide yes)
			(effects
				(font
					(size 1.27 1.27)
				)
			)
		)
		(property "Value" "2R6F-GP"
			(at -0.0508 -4.8514 270)
			(unlocked yes)
			(layer "F.Fab")
			(hide yes)
			(effects
				(font
					(size 1.016 1.016)
					(thickness 0.1524)
				)
			)
		)
		(property "Device Type" "R1206H26"
			(at 0 -6.3754 270)
			(unlocked yes)
			(layer "F.Fab")
			(hide yes)
			(effects
				(font
					(size 1.016 1.016)
					(thickness 0.1524)
				)
			)
		)
		(duplicate_pad_numbers_are_jumpers no)
		(fp_line
			(start -1.016 2.2352)
			(end -1.016 -2.2352)
			(stroke
				(width 0.1524)
				(type default)
			)
			(layer "F.SilkS")
		)
		(fp_line
			(start 1.016 2.2352)
			(end -1.016 2.2352)
			(stroke
				(width 0.1524)
				(type default)
			)
			(layer "F.SilkS")
		)
		(fp_line
			(start -1.016 -2.2352)
			(end 1.016 -2.2352)
			(stroke
				(width 0.1524)
				(type default)
			)
			(layer "F.SilkS")
		)
		(fp_line
			(start 1.016 -2.2352)
			(end 1.016 2.2352)
			(stroke
				(width 0.1524)
				(type default)
			)
			(layer "F.SilkS")
		)
		(fp_rect
			(start -1.0922 2.3114)
			(end 1.0922 -2.3114)
			(stroke
				(width 0)
				(type default)
			)
			(fill no)
			(layer "F.CrtYd")
		)
		(fp_poly
			(pts
				(xy -1.0922 -2.3114) (xy 1.0922 -2.3114) (xy 1.0922 2.3114) (xy -1.0922 2.3114)
			)
			(stroke
				(width 0)
				(type default)
			)
			(fill no)
			(layer "F.Fab")
		)
		(pad "1" smd rect
			(at 0 -1.397 270)
			(size 1.651 1.27)
			(layers "F.Cu" "F.Mask" "F.Paste")
			(net "P12V_HDD32")
		)
		(pad "2" smd rect
			(at 0 1.397 270)
			(size 1.651 1.27)
			(layers "F.Cu" "F.Mask" "F.Paste")
			(net "12V_PRE_32")
		)
	)
	(footprint ""
		(layer "F.Cu")
		(at 473.1258 -179.6288 90)
		(property "Reference" "R660"
			(at 0 0 90)
			(layer "F.SilkS")
			(hide yes)
			(effects
				(font
					(size 1.27 1.27)
				)
			)
		)
		(property "Value" "2R6F-GP"
			(at -0.0508 -4.8514 90)
			(unlocked yes)
			(layer "F.Fab")
			(hide yes)
			(effects
				(font
					(size 1.016 1.016)
					(thickness 0.1524)
				)
			)
		)
		(property "Device Type" "R1206H26"
			(at 0 -6.3754 90)
			(unlocked yes)
			(layer "F.Fab")
			(hide yes)
			(effects
				(font
					(size 1.016 1.016)
					(thickness 0.1524)
				)
			)
		)
		(duplicate_pad_numbers_are_jumpers no)
		(fp_line
			(start 1.016 -2.2352)
			(end 1.016 2.2352)
			(stroke
				(width 0.1524)
				(type default)
			)
			(layer "F.SilkS")
		)
		(fp_line
			(start -1.016 -2.2352)
			(end 1.016 -2.2352)
			(stroke
				(width 0.1524)
				(type default)
			)
			(layer "F.SilkS")
		)
		(fp_line
			(start 1.016 2.2352)
			(end -1.016 2.2352)
			(stroke
				(width 0.1524)
				(type default)
			)
			(layer "F.SilkS")
		)
		(fp_line
			(start -1.016 2.2352)
			(end -1.016 -2.2352)
			(stroke
				(width 0.1524)
				(type default)
			)
			(layer "F.SilkS")
		)
		(fp_rect
			(start -1.0922 2.3114)
			(end 1.0922 -2.3114)
			(stroke
				(width 0)
				(type default)
			)
			(fill no)
			(layer "F.CrtYd")
		)
		(fp_poly
			(pts
				(xy -1.0922 -2.3114) (xy 1.0922 -2.3114) (xy 1.0922 2.3114) (xy -1.0922 2.3114)
			)
			(stroke
				(width 0)
				(type default)
			)
			(fill no)
			(layer "F.Fab")
		)
		(pad "1" smd rect
			(at 0 -1.397 90)
			(size 1.651 1.27)
			(layers "F.Cu" "F.Mask" "F.Paste")
			(net "P12V_HDD23")
		)
		(pad "2" smd rect
			(at 0 1.397 90)
			(size 1.651 1.27)
			(layers "F.Cu" "F.Mask" "F.Paste")
			(net "12V_PRE_23")
		)
	)
	(footprint ""
		(layer "F.Cu")
		(at 149.196298 -276.065742 -90)
		(property "Reference" "R231"
			(at 0 0 270)
			(layer "F.SilkS")
			(hide yes)
			(effects
				(font
					(size 1.27 1.27)
				)
			)
		)
		(property "Value" "1KR2F-3-GP"
			(at 0.064008 -3.993896 270)
			(unlocked yes)
			(layer "F.Fab")
			(hide yes)
			(effects
				(font
					(size 1.016 1.016)
					(thickness 0.1524)
				)
			)
		)
		(property "Device Type" "R402H16"
			(at 0.064008 -5.517896 270)
			(unlocked yes)
			(layer "F.Fab")
			(hide yes)
			(effects
				(font
					(size 1.016 1.016)
					(thickness 0.1524)
				)
			)
		)
		(duplicate_pad_numbers_are_jumpers no)
		(fp_line
			(start -0.508 -0.9398)
			(end -0.508 0.9398)
			(stroke
				(width 0.1524)
				(type default)
			)
			(layer "F.SilkS")
		)
		(fp_line
			(start 0.508 -0.9398)
			(end -0.508 -0.9398)
			(stroke
				(width 0.1524)
				(type default)
			)
			(layer "F.SilkS")
		)
		(fp_rect
			(start -0.508 0.9398)
			(end 0.508 -0.9398)
			(stroke
				(width 0)
				(type default)
			)
			(fill no)
			(layer "F.CrtYd")
		)
		(fp_rect
			(start -0.508 0.9398)
			(end 0.508 -0.9398)
			(stroke
				(width 0)
				(type default)
			)
			(fill no)
			(layer "F.Fab")
		)
		(pad "1" smd custom
			(at 0 -0.4445 270)
			(size 0.1397 0.1397)
			(layers "F.Cu" "F.Mask" "F.Paste")
			(net "P3V3_STBY_A")
			(options
				(clearance outline)
				(anchor circle)
			)
			(primitives
				(gr_poly
					(pts
						(arc
							(start -0.1778 -0.2794)
							(mid -0.249642 -0.249642)
							(end -0.2794 -0.1778)
						)
						(arc
							(start -0.2794 0.1778)
							(mid -0.249642 0.249642)
							(end -0.1778 0.2794)
						)
						(arc
							(start 0.1778 0.2794)
							(mid 0.249642 0.249642)
							(end 0.2794 0.1778)
						)
						(arc
							(start 0.2794 -0.1778)
							(mid 0.249642 -0.249642)
							(end 0.1778 -0.2794)
						)
					)
					(width 0)
					(fill yes)
				)
			)
		)
		(pad "2" smd custom
			(at 0 0.4445 270)
			(size 0.1397 0.1397)
			(layers "F.Cu" "F.Mask" "F.Paste")
			(net "SW_PWR_R_HDD4")
			(options
				(clearance outline)
				(anchor circle)
			)
			(primitives
				(gr_poly
					(pts
						(arc
							(start -0.1778 -0.2794)
							(mid -0.249642 -0.249642)
							(end -0.2794 -0.1778)
						)
						(arc
							(start -0.2794 0.1778)
							(mid -0.249642 0.249642)
							(end -0.1778 0.2794)
						)
						(arc
							(start 0.1778 0.2794)
							(mid 0.249642 0.249642)
							(end 0.2794 0.1778)
						)
						(arc
							(start 0.2794 -0.1778)
							(mid 0.249642 -0.249642)
							(end 0.1778 -0.2794)
						)
					)
					(width 0)
					(fill yes)
				)
			)
		)
	)
)
